(kicad_pcb
	(version 20221018)
	(generator pcbnew)
	(general
    (thickness 1.518)
  )
	(paper "A4")
	(title_block
    (title "Kria K26 Devboard")
    (date "2024-03-26")
    (rev "1.2.5")
    (comment 1 "www.antmicro.com")
    (comment 2 "Antmicro Ltd.")
		(comment 9 "footprints 581-588 of 660")
	)
	(layers
    (0 "F.Cu" mixed)
    (1 "In1.Cu" power)
    (2 "In2.Cu" mixed)
    (3 "In3.Cu" power)
    (4 "In4.Cu" mixed)
    (5 "In5.Cu" power)
    (6 "In6.Cu" mixed)
    (31 "B.Cu" power)
    (32 "B.Adhes" user "B.Adhesive")
    (33 "F.Adhes" user "F.Adhesive")
    (34 "B.Paste" user)
    (35 "F.Paste" user)
    (36 "B.SilkS" user "B.Silkscreen")
    (37 "F.SilkS" user "F.Silkscreen")
    (38 "B.Mask" user)
    (39 "F.Mask" user)
    (40 "Dwgs.User" user "User.Drawings")
    (41 "Cmts.User" user "User.Comments")
    (42 "Eco1.User" user "User.Eco1")
    (43 "Eco2.User" user "User.Eco2")
    (44 "Edge.Cuts" user)
    (45 "Margin" user)
    (46 "B.CrtYd" user "B.Courtyard")
    (47 "F.CrtYd" user "F.Courtyard")
    (48 "B.Fab" user)
    (49 "F.Fab" user)
  )
	(footprint "kria-k26-devboard-footprints:C_0402_1005Metric" (layer "B.Cu")
    (at 144.57 73 180)
    (descr "Capacitor SMD 0402")
    (tags "capacitor SMD 0402")
    (property "Author" "Antmicro")
    (property "Dielectric" "")
    (property "License" "Apache-2.0")
    (property "MPN" "C1005X6S1A105K050BC")
    (property "Manufacturer" "TDK")
    (property "Sheetfile" "dc-dc-conventers.kicad_sch")
    (property "Sheetname" "DC/DC conventers")
    (property "Val" "1u")
    (property "Voltage" "")
    (property "ki_description" " ")
    (attr smd)
    (fp_text reference "C187" (at 0.825 -0.44) (layer "B.SilkS")
        (effects (font (size 0.7 0.7) (thickness 0.15)) (justify left bottom mirror))
    )
    (fp_text value "C_1u_0402" (at 0 -1.4) (layer "B.Fab") hide
        (effects (font (size 0.7 0.7) (thickness 0.15)) (justify left bottom mirror))
    )
    (fp_text user "${REFERENCE}" (at -0.932 -3.168) (layer "B.Fab") hide
        (effects (font (size 0.7 0.7) (thickness 0.15)) (justify left bottom mirror))
    )
    (fp_text user "License: Apache-2.0" (at -0.932 -5.17) (layer "B.Fab") hide
        (effects (font (size 0.7 0.7) (thickness 0.15)) (justify left bottom mirror))
    )
    (fp_text user "Author: Antmicro" (at -0.932 -4.17) (layer "B.Fab") hide
        (effects (font (size 0.7 0.7) (thickness 0.15)) (justify left bottom mirror))
    )
    (fp_rect (start -0.94 0.47) (end 0.94 -0.47)
      (stroke (width 0.05) (type solid)) (fill none) (layer "B.CrtYd"))
    (fp_rect (start -0.499 0.249) (end 0.499 -0.249)
      (stroke (width 0.15) (type solid)) (fill none) (layer "B.Fab"))
    (pad "1" smd roundrect (at -0.484 0 180) (size 0.59 0.64) (layers "B.Cu" "B.Paste" "B.Mask") (roundrect_rratio 0.25)
      (net 248 "Net-(U47-PVCC)") (pintype "passive"))
    (pad "2" smd roundrect (at 0.484 0 180) (size 0.59 0.64) (layers "B.Cu" "B.Paste" "B.Mask") (roundrect_rratio 0.25)
      (net 1 "GND") (pintype "passive"))
  )
	(footprint "kria-k26-devboard-footprints:UQFN-13_2x3mm_P0.5mm" (layer "B.Cu")
    (at 147.675 73.55 90)
    (property "Author" "Antmicro")
    (property "License" "Apache-2.0")
    (property "MPN" "RT6236AHGQUF")
    (property "Manufacturer" "Richtek")
    (property "Sheetfile" "dc-dc-conventers.kicad_sch")
    (property "Sheetname" "DC/DC conventers")
    (property "ki_description" "DC-DC Switching Buck Step Down Regulator, Adjustable, 4.5V-18Vin, 700mV-8V/6A out, 650kHz, UQFN-13")
    (property "ki_keywords" "SMT, PMIC, IC, SWITCHING, VOLTAGE, REGULATOR, DC-DC")
    (attr smd)
    (fp_text reference "U47" (at 1.46 -1.615) (layer "B.SilkS")
        (effects (font (size 0.7 0.7) (thickness 0.15)) (justify left bottom mirror))
    )
    (fp_text value "RT6236AHGQUF" (at 0.812 -3.293 270) (layer "B.Fab") hide
        (effects (font (size 0.7 0.7) (thickness 0.15)) (justify left bottom mirror))
    )
    (fp_text user "License: Apache-2.0" (at -1.537 -7.693 270) (layer "B.Fab") hide
        (effects (font (size 0.7 0.7) (thickness 0.15)) (justify left bottom mirror))
    )
    (fp_text user "${REFERENCE}" (at -1.537 -5.294 270) (layer "B.Fab") hide
        (effects (font (size 0.7 0.7) (thickness 0.15)) (justify left bottom mirror))
    )
    (fp_text user "Author: Antmicro" (at -1.537 -6.493 270) (layer "B.Fab") hide
        (effects (font (size 0.7 0.7) (thickness 0.15)) (justify left bottom mirror))
    )
    (fp_circle (center -1.25 1.65) (end -1.2 1.65)
      (stroke (width 0.15) (type solid)) (fill solid) (layer "B.SilkS"))
    (fp_rect (start -1.65 2.15) (end 1.65 -2.15)
      (stroke (width 0.05) (type solid)) (fill none) (layer "B.CrtYd"))
    (fp_line (start -0.9 -1.3) (end -0.9 0.85)
      (stroke (width 0.15) (type solid)) (layer "B.Fab"))
    (fp_line (start -0.9 0.85) (end -0.45 1.3)
      (stroke (width 0.15) (type solid)) (layer "B.Fab"))
    (fp_line (start -0.45 1.3) (end 0.9 1.3)
      (stroke (width 0.15) (type solid)) (layer "B.Fab"))
    (fp_line (start 0.9 -1.3) (end -0.9 -1.3)
      (stroke (width 0.15) (type solid)) (layer "B.Fab"))
    (fp_line (start 0.9 1.3) (end 0.9 -1.3)
      (stroke (width 0.15) (type solid)) (layer "B.Fab"))
    (pad "1" smd roundrect (at -1 0.75 270) (size 0.8 0.3) (layers "B.Cu" "B.Paste" "B.Mask") (roundrect_rratio 0.25)
      (net 1 "GND") (pinfunction "GND") (pintype "power_in") (zone_connect 2))
    (pad "2" smd roundrect (at -1 0.25 270) (size 0.8 0.3) (layers "B.Cu" "B.Paste" "B.Mask") (roundrect_rratio 0.25)
      (net 685 "Net-(U47-EN)") (pinfunction "EN") (pintype "input") (zone_connect 2))
    (pad "3" smd roundrect (at -1 -0.248 270) (size 0.8 0.3) (layers "B.Cu" "B.Paste" "B.Mask") (roundrect_rratio 0.25)
      (net 254 "Net-(U47-FB)") (pinfunction "FB") (pintype "input") (zone_connect 2))
    (pad "4" smd roundrect (at -1 -0.748 270) (size 0.8 0.3) (layers "B.Cu" "B.Paste" "B.Mask") (roundrect_rratio 0.25)
      (net 779 "unconnected-(U47-NC-Pad4)") (pinfunction "NC") (pintype "no_connect") (zone_connect 2))
    (pad "5" smd roundrect (at -0.25 -0.998) (size 1.8 0.3) (layers "B.Cu" "B.Paste" "B.Mask") (roundrect_rratio 0.25)
      (net 250 "Net-(U47-SS)") (pinfunction "SS") (pintype "input") (zone_connect 2))
    (pad "6" smd roundrect (at 0.248 -0.998) (size 1.8 0.3) (layers "B.Cu" "B.Paste" "B.Mask") (roundrect_rratio 0.25)
      (net 248 "Net-(U47-PVCC)") (pinfunction "PVCC") (pintype "output") (zone_connect 2))
    (pad "7" smd roundrect (at 0.998 -0.748 270) (size 0.8 0.3) (layers "B.Cu" "B.Paste" "B.Mask") (roundrect_rratio 0.25)
      (net 780 "unconnected-(U47-NC-Pad7)") (pinfunction "NC") (pintype "no_connect") (zone_connect 2))
    (pad "8" smd roundrect (at 0.998 -0.248 270) (size 0.8 0.3) (layers "B.Cu" "B.Paste" "B.Mask") (roundrect_rratio 0.25)
      (net 781 "unconnected-(U47-PG-Pad8)") (pinfunction "PG") (pintype "output+no_connect") (zone_connect 2))
    (pad "9" smd roundrect (at 0.998 0.25 270) (size 0.8 0.3) (layers "B.Cu" "B.Paste" "B.Mask") (roundrect_rratio 0.25)
      (net 14 "/Power Supply/DC/DC conventers/DC_MAIN_BUS") (pinfunction "VIN") (pintype "passive") (zone_connect 2))
    (pad "10" smd roundrect (at 0.998 0.75 270) (size 0.8 0.3) (layers "B.Cu" "B.Paste" "B.Mask") (roundrect_rratio 0.25)
      (net 14 "/Power Supply/DC/DC conventers/DC_MAIN_BUS") (pinfunction "VIN") (pintype "power_in") (zone_connect 2))
    (pad "11" smd roundrect (at 0.583 1.476) (size 0.85 0.3) (layers "B.Cu" "B.Paste" "B.Mask") (roundrect_rratio 0.25)
      (net 252 "Net-(U47-BOOT)") (pinfunction "BOOT") (pintype "output") (zone_connect 2))
    (pad "12" smd roundrect (at -0.003 1.2 180) (size 1.4 0.47) (layers "B.Cu" "B.Paste" "B.Mask") (roundrect_rratio 0.25)
      (net 365 "/Power Supply/DC/DC conventers/SW_USB_5V") (pinfunction "SW") (pintype "power_out") (zone_connect 2))
    (pad "13" smd roundrect (at -0.585 1.476) (size 0.85 0.3) (layers "B.Cu" "B.Paste" "B.Mask") (roundrect_rratio 0.25)
      (net 1 "GND") (pinfunction "GND") (pintype "passive") (zone_connect 2))
  )
	(footprint "kria-k26-devboard-footprints:C_0603_1608Metric" (layer "B.Cu")
    (at 147.37 71.18 180)
    (descr "Capacitor SMD 0603")
    (tags "capacitor 0603")
    (property "Author" "Antmicro")
    (property "Dielectric" "")
    (property "License" "Apache-2.0")
    (property "MPN" "C1608X5R1E106M080AC")
    (property "Manufacturer" "TDK")
    (property "Sheetfile" "dc-dc-conventers.kicad_sch")
    (property "Sheetname" "DC/DC conventers")
    (property "Val" "10u/25V")
    (property "Voltage" "")
    (property "ki_description" " ")
    (attr smd)
    (fp_text reference "C185" (at -1.44 2.11) (layer "B.SilkS")
        (effects (font (size 0.7 0.7) (thickness 0.15)) (justify left bottom mirror))
    )
    (fp_text value "C_10u_25V_0603" (at 0 -1.6) (layer "B.Fab") hide
        (effects (font (size 0.7 0.7) (thickness 0.15)) (justify left bottom mirror))
    )
    (fp_text user "Author: Antmicro" (at -1.682 -4.894) (layer "B.Fab") hide
        (effects (font (size 0.7 0.7) (thickness 0.15)) (justify left bottom mirror))
    )
    (fp_text user "${REFERENCE}" (at -1.682 -3.895) (layer "B.Fab") hide
        (effects (font (size 0.7 0.7) (thickness 0.15)) (justify left bottom mirror))
    )
    (fp_text user "License: Apache-2.0" (at -1.682 -5.895) (layer "B.Fab") hide
        (effects (font (size 0.7 0.7) (thickness 0.15)) (justify left bottom mirror))
    )
    (fp_line (start -0.3 -0.3) (end 0.3 -0.3)
      (stroke (width 0.15) (type solid)) (layer "B.SilkS"))
    (fp_line (start -0.3 0.3) (end 0.3 0.3)
      (stroke (width 0.15) (type solid)) (layer "B.SilkS"))
    (fp_rect (start -1.24 0.7) (end 1.24 -0.7)
      (stroke (width 0.05) (type solid)) (fill none) (layer "B.CrtYd"))
    (fp_rect (start -0.8 0.4) (end 0.8 -0.4)
      (stroke (width 0.15) (type solid)) (fill none) (layer "B.Fab"))
    (pad "1" smd roundrect (at -0.7 0 180) (size 0.6 0.8) (layers "B.Cu" "B.Paste" "B.Mask") (roundrect_rratio 0.2)
      (net 14 "/Power Supply/DC/DC conventers/DC_MAIN_BUS") (pintype "passive"))
    (pad "2" smd roundrect (at 0.7 0 180) (size 0.6 0.8) (layers "B.Cu" "B.Paste" "B.Mask") (roundrect_rratio 0.2)
      (net 1 "GND") (pintype "passive"))
  )
	(footprint "kria-k26-devboard-footprints:C_0603_1608Metric" (layer "B.Cu")
    (at 135.7122 83.4644 90)
    (descr "Capacitor SMD 0603")
    (tags "capacitor 0603")
    (property "Author" "Antmicro")
    (property "Dielectric" "")
    (property "License" "Apache-2.0")
    (property "MPN" "GRM188R60J226MEA0D")
    (property "Manufacturer" "Murata")
    (property "Sheetfile" "dc-dc-conventers.kicad_sch")
    (property "Sheetname" "DC/DC conventers")
    (property "Val" "22u")
    (property "Voltage" "")
    (property "ki_description" " ")
    (attr smd)
    (fp_text reference "C212" (at 1.4844 -0.8122 270) (layer "B.SilkS")
        (effects (font (size 0.7 0.7) (thickness 0.15)) (justify left bottom mirror))
    )
    (fp_text value "C_22u_0603" (at 0 -1.6 270) (layer "B.Fab") hide
        (effects (font (size 0.7 0.7) (thickness 0.15)) (justify left bottom mirror))
    )
    (fp_text user "Author: Antmicro" (at -1.682 -4.894 270) (layer "B.Fab") hide
        (effects (font (size 0.7 0.7) (thickness 0.15)) (justify left bottom mirror))
    )
    (fp_text user "License: Apache-2.0" (at -1.682 -5.895 270) (layer "B.Fab") hide
        (effects (font (size 0.7 0.7) (thickness 0.15)) (justify left bottom mirror))
    )
    (fp_text user "${REFERENCE}" (at -1.682 -3.895 270) (layer "B.Fab") hide
        (effects (font (size 0.7 0.7) (thickness 0.15)) (justify left bottom mirror))
    )
    (fp_line (start -0.3 -0.3) (end 0.3 -0.3)
      (stroke (width 0.15) (type solid)) (layer "B.SilkS"))
    (fp_line (start -0.3 0.3) (end 0.3 0.3)
      (stroke (width 0.15) (type solid)) (layer "B.SilkS"))
    (fp_rect (start -1.24 0.7) (end 1.24 -0.7)
      (stroke (width 0.05) (type solid)) (fill none) (layer "B.CrtYd"))
    (fp_rect (start -0.8 0.4) (end 0.8 -0.4)
      (stroke (width 0.15) (type solid)) (fill none) (layer "B.Fab"))
    (pad "1" smd roundrect (at -0.7 0 90) (size 0.6 0.8) (layers "B.Cu" "B.Paste" "B.Mask") (roundrect_rratio 0.2)
      (net 766 "/Power Supply/DC/DC conventers/PS_2V5_OUT") (pintype "passive"))
    (pad "2" smd roundrect (at 0.7 0 90) (size 0.6 0.8) (layers "B.Cu" "B.Paste" "B.Mask") (roundrect_rratio 0.2)
      (net 1 "GND") (pintype "passive"))
  )
	(footprint "kria-k26-devboard-footprints:R_0402_1005Metric" (layer "B.Cu")
    (at 143.025 80.475 90)
    (descr "Resistor SMD 0402")
    (tags "resistor SMD 0402")
    (property "Author" "Antmicro")
    (property "License" "Apache-2.0")
    (property "MPN" "CR0402-FX-2152GLF")
    (property "Manufacturer" "Bourns")
    (property "Sheetfile" "dc-dc-conventers.kicad_sch")
    (property "Sheetname" "DC/DC conventers")
    (property "Tolerance" "1%")
    (property "Val" "21k5")
    (property "ki_description" "21k5 resistor in 0402 package with 1% tolerance")
    (attr smd)
    (fp_text reference "R133" (at 1.205 1.355 270) (layer "B.SilkS")
        (effects (font (size 0.7 0.7) (thickness 0.15)) (justify left bottom mirror))
    )
    (fp_text value "R_21k5_0402" (at 0 -1.4 270) (layer "B.Fab") hide
        (effects (font (size 0.7 0.7) (thickness 0.15)) (justify left bottom mirror))
    )
    (fp_text user "Author: Antmicro" (at -0.95 -4.169 270) (layer "B.Fab") hide
        (effects (font (size 0.7 0.7) (thickness 0.15)) (justify left bottom mirror))
    )
    (fp_text user "${REFERENCE}" (at -0.95 -3.168 270) (layer "B.Fab") hide
        (effects (font (size 0.7 0.7) (thickness 0.15)) (justify left bottom mirror))
    )
    (fp_text user "License: Apache-2.0" (at -0.95 -5.169 270) (layer "B.Fab") hide
        (effects (font (size 0.7 0.7) (thickness 0.15)) (justify left bottom mirror))
    )
    (fp_rect (start -0.93 0.47) (end 0.93 -0.47)
      (stroke (width 0.05) (type solid)) (fill none) (layer "B.CrtYd"))
    (fp_rect (start -0.5 0.25) (end 0.5 -0.25)
      (stroke (width 0.15) (type solid)) (fill none) (layer "B.Fab"))
    (pad "1" smd roundrect (at -0.485 0 90) (size 0.59 0.64) (layers "B.Cu" "B.Paste" "B.Mask") (roundrect_rratio 0.25)
      (net 766 "/Power Supply/DC/DC conventers/PS_2V5_OUT") (pintype "passive"))
    (pad "2" smd roundrect (at 0.485 0 90) (size 0.59 0.64) (layers "B.Cu" "B.Paste" "B.Mask") (roundrect_rratio 0.25)
      (net 689 "Net-(U50-FB)") (pintype "passive"))
  )
	(footprint "kria-k26-devboard-footprints:C_0402_1005Metric" (layer "B.Cu")
    (at 141.315 83.14 180)
    (descr "Capacitor SMD 0402")
    (tags "capacitor SMD 0402")
    (property "Author" "Antmicro")
    (property "Dielectric" "X5R")
    (property "License" "Apache-2.0")
    (property "MPN" "GRM155R61H104KE14D")
    (property "Manufacturer" "Murata")
    (property "Sheetfile" "dc-dc-conventers.kicad_sch")
    (property "Sheetname" "DC/DC conventers")
    (property "Val" "100n")
    (property "Voltage" "50V")
    (property "ki_description" " ")
    (attr smd)
    (fp_text reference "C207" (at -3.725 -0.37) (layer "B.SilkS")
        (effects (font (size 0.7 0.7) (thickness 0.15)) (justify left bottom mirror))
    )
    (fp_text value "C_100n_0402" (at 0 -1.4) (layer "B.Fab") hide
        (effects (font (size 0.7 0.7) (thickness 0.15)) (justify left bottom mirror))
    )
    (fp_text user "License: Apache-2.0" (at -0.932 -5.17) (layer "B.Fab") hide
        (effects (font (size 0.7 0.7) (thickness 0.15)) (justify left bottom mirror))
    )
    (fp_text user "Author: Antmicro" (at -0.932 -4.17) (layer "B.Fab") hide
        (effects (font (size 0.7 0.7) (thickness 0.15)) (justify left bottom mirror))
    )
    (fp_text user "${REFERENCE}" (at -0.932 -3.168) (layer "B.Fab") hide
        (effects (font (size 0.7 0.7) (thickness 0.15)) (justify left bottom mirror))
    )
    (fp_rect (start -0.94 0.47) (end 0.94 -0.47)
      (stroke (width 0.05) (type solid)) (fill none) (layer "B.CrtYd"))
    (fp_rect (start -0.499 0.249) (end 0.499 -0.249)
      (stroke (width 0.15) (type solid)) (fill none) (layer "B.Fab"))
    (pad "1" smd roundrect (at -0.484 0 180) (size 0.59 0.64) (layers "B.Cu" "B.Paste" "B.Mask") (roundrect_rratio 0.25)
      (net 258 "Net-(U50-BST)") (pintype "passive"))
    (pad "2" smd roundrect (at 0.484 0 180) (size 0.59 0.64) (layers "B.Cu" "B.Paste" "B.Mask") (roundrect_rratio 0.25)
      (net 310 "/Power Supply/DC/DC conventers/SW_PS_2V5") (pintype "passive"))
  )
	(footprint "kria-k26-devboard-footprints:C_0603_1608Metric" (layer "B.Cu")
    (at 137.8 80.675001 -90)
    (descr "Capacitor SMD 0603")
    (tags "capacitor 0603")
    (property "Author" "Antmicro")
    (property "Dielectric" "")
    (property "License" "Apache-2.0")
    (property "MPN" "C1608X5R1E106M080AC")
    (property "Manufacturer" "TDK")
    (property "Sheetfile" "dc-dc-conventers.kicad_sch")
    (property "Sheetname" "DC/DC conventers")
    (property "Val" "10u/25V")
    (property "Voltage" "")
    (property "ki_description" " ")
    (attr smd)
    (fp_text reference "C202" (at -1.395001 0.82 90) (layer "B.SilkS")
        (effects (font (size 0.7 0.7) (thickness 0.15)) (justify left bottom mirror))
    )
    (fp_text value "C_10u_25V_0603" (at 0 -1.6 90) (layer "B.Fab") hide
        (effects (font (size 0.7 0.7) (thickness 0.15)) (justify left bottom mirror))
    )
    (fp_text user "${REFERENCE}" (at -1.682 -3.895 90) (layer "B.Fab") hide
        (effects (font (size 0.7 0.7) (thickness 0.15)) (justify left bottom mirror))
    )
    (fp_text user "License: Apache-2.0" (at -1.682 -5.895 90) (layer "B.Fab") hide
        (effects (font (size 0.7 0.7) (thickness 0.15)) (justify left bottom mirror))
    )
    (fp_text user "Author: Antmicro" (at -1.682 -4.894 90) (layer "B.Fab") hide
        (effects (font (size 0.7 0.7) (thickness 0.15)) (justify left bottom mirror))
    )
    (fp_line (start -0.3 -0.3) (end 0.3 -0.3)
      (stroke (width 0.15) (type solid)) (layer "B.SilkS"))
    (fp_line (start -0.3 0.3) (end 0.3 0.3)
      (stroke (width 0.15) (type solid)) (layer "B.SilkS"))
    (fp_rect (start -1.24 0.7) (end 1.24 -0.7)
      (stroke (width 0.05) (type solid)) (fill none) (layer "B.CrtYd"))
    (fp_rect (start -0.8 0.4) (end 0.8 -0.4)
      (stroke (width 0.15) (type solid)) (fill none) (layer "B.Fab"))
    (pad "1" smd roundrect (at -0.7 0 270) (size 0.6 0.8) (layers "B.Cu" "B.Paste" "B.Mask") (roundrect_rratio 0.2)
      (net 14 "/Power Supply/DC/DC conventers/DC_MAIN_BUS") (pintype "passive"))
    (pad "2" smd roundrect (at 0.7 0 270) (size 0.6 0.8) (layers "B.Cu" "B.Paste" "B.Mask") (roundrect_rratio 0.2)
      (net 1 "GND") (pintype "passive"))
  )
	(footprint "kria-k26-devboard-footprints:R_0402_1005Metric" (layer "B.Cu")
    (at 142.6 78.8 180)
    (descr "Resistor SMD 0402")
    (tags "resistor SMD 0402")
    (property "Author" "Antmicro")
    (property "License" "Apache-2.0")
    (property "MPN" "CR0402-FX-1002GLF")
    (property "Manufacturer" "Bourns")
    (property "Sheetfile" "dc-dc-conventers.kicad_sch")
    (property "Sheetname" "DC/DC conventers")
    (property "Tolerance" "1%")
    (property "Val" "10k")
    (property "ki_description" "10k resistor in 0402 package with 1% tolerance")
    (attr smd)
    (fp_text reference "R134" (at -1.28 0.61) (layer "B.SilkS")
        (effects (font (size 0.7 0.7) (thickness 0.15)) (justify left bottom mirror))
    )
    (fp_text value "R_10k_0402" (at 0 -1.4) (layer "B.Fab") hide
        (effects (font (size 0.7 0.7) (thickness 0.15)) (justify left bottom mirror))
    )
    (fp_text user "License: Apache-2.0" (at -0.95 -5.169) (layer "B.Fab") hide
        (effects (font (size 0.7 0.7) (thickness 0.15)) (justify left bottom mirror))
    )
    (fp_text user "${REFERENCE}" (at -0.95 -3.168) (layer "B.Fab") hide
        (effects (font (size 0.7 0.7) (thickness 0.15)) (justify left bottom mirror))
    )
    (fp_text user "Author: Antmicro" (at -0.95 -4.169) (layer "B.Fab") hide
        (effects (font (size 0.7 0.7) (thickness 0.15)) (justify left bottom mirror))
    )
    (fp_rect (start -0.93 0.47) (end 0.93 -0.47)
      (stroke (width 0.05) (type solid)) (fill none) (layer "B.CrtYd"))
    (fp_rect (start -0.5 0.25) (end 0.5 -0.25)
      (stroke (width 0.15) (type solid)) (fill none) (layer "B.Fab"))
    (pad "1" smd roundrect (at -0.485 0 180) (size 0.59 0.64) (layers "B.Cu" "B.Paste" "B.Mask") (roundrect_rratio 0.25)
      (net 689 "Net-(U50-FB)") (pintype "passive"))
    (pad "2" smd roundrect (at 0.485 0 180) (size 0.59 0.64) (layers "B.Cu" "B.Paste" "B.Mask") (roundrect_rratio 0.25)
      (net 1 "GND") (pintype "passive"))
  )
)
